(kicad_pcb
	(version 20260206)
	(generator "pcbnew")
	(generator_version "10.0")
	(general
		(thickness 1.6)
		(legacy_teardrops no)
	)
	(paper "A4")
	(title_block
		(title "Bryce Canyon_Front Panel_16369-1_OCP.brd")
		(comment 1 "Bryce Canyon / footprints 147-154 of 154")
	)
	(layers
		(0 "F.Cu" signal "TOP")
		(4 "In1.Cu" signal "L2GND")
		(6 "In2.Cu" signal "L3VCC")
		(2 "B.Cu" signal "BOTTOM")
		(9 "F.Adhes" user "F.Adhesive")
		(11 "B.Adhes" user "B.Adhesive")
		(13 "F.Paste" user "Package Geometry/Pastemask Top")
		(15 "B.Paste" user "Package Geometry/Pastemask Bottom")
		(5 "F.SilkS" user "Ref Des/Silkscreen Top")
		(7 "B.SilkS" user "Ref Des/Silkscreen Bottom")
		(1 "F.Mask" user "Board Geometry/Soldermask Top")
		(3 "B.Mask" user "Board Geometry/Soldermask Bottom")
		(17 "Dwgs.User" user "User.Drawings")
		(19 "Cmts.User" user "User.Comments")
		(21 "Eco1.User" user "User.Eco1")
		(23 "Eco2.User" user "User.Eco2")
		(25 "Edge.Cuts" user "Board Geometry/Outline")
		(27 "Margin" user)
		(31 "F.CrtYd" user "Package Geometry/Place Bound Top")
		(29 "B.CrtYd" user "Package Geometry/Place Bound Bottom")
		(35 "F.Fab" user "Ref Des/Assembly Top")
		(33 "B.Fab" user "Ref Des/Assembly Bottom")
	)
	(footprint ""
		(layer "F.Cu")
		(at 8.9408 -15.9004 -90)
		(property "Reference" "R5"
			(at 0 0 270)
			(layer "F.SilkS")
			(hide yes)
			(effects
				(font
					(size 1.27 1.27)
				)
			)
		)
		(property "Value" "0R2J-2-GP"
			(at 0.064008 -4.679696 270)
			(unlocked yes)
			(layer "F.Fab")
			(hide yes)
			(effects
				(font
					(size 2.54 2.54)
					(thickness 0.381)
				)
			)
		)
		(property "Device Type" "R402H16"
			(at 0.064008 -6.203696 270)
			(unlocked yes)
			(layer "F.Fab")
			(hide yes)
			(effects
				(font
					(size 2.54 2.54)
					(thickness 0.381)
				)
			)
		)
		(duplicate_pad_numbers_are_jumpers no)
		(fp_line
			(start -0.508 -0.9398)
			(end -0.508 0.9398)
			(stroke
				(width 0.1524)
				(type default)
			)
			(layer "F.SilkS")
		)
		(fp_line
			(start 0.508 -0.9398)
			(end -0.508 -0.9398)
			(stroke
				(width 0.1524)
				(type default)
			)
			(layer "F.SilkS")
		)
		(fp_rect
			(start -0.508 0.9398)
			(end 0.508 -0.9398)
			(stroke
				(width 0)
				(type default)
			)
			(fill no)
			(layer "F.CrtYd")
		)
		(fp_rect
			(start -0.508 0.9398)
			(end 0.508 -0.9398)
			(stroke
				(width 0)
				(type default)
			)
			(fill no)
			(layer "F.Fab")
		)
		(pad "1" smd custom
			(at 0 -0.4445 270)
			(size 0.1397 0.1397)
			(layers "F.Cu" "F.Mask" "F.Paste")
			(net "I2C_DEBUG_A_SDA_R")
			(options
				(clearance outline)
				(anchor circle)
			)
			(primitives
				(gr_poly
					(pts
						(arc
							(start -0.1778 -0.2794)
							(mid -0.249642 -0.249642)
							(end -0.2794 -0.1778)
						)
						(arc
							(start -0.2794 0.1778)
							(mid -0.249642 0.249642)
							(end -0.1778 0.2794)
						)
						(arc
							(start 0.1778 0.2794)
							(mid 0.249642 0.249642)
							(end 0.2794 0.1778)
						)
						(arc
							(start 0.2794 -0.1778)
							(mid 0.249642 -0.249642)
							(end 0.1778 -0.2794)
						)
					)
					(width 0)
					(fill yes)
				)
			)
		)
		(pad "2" smd custom
			(at 0 0.4445 270)
			(size 0.1397 0.1397)
			(layers "F.Cu" "F.Mask" "F.Paste")
			(net "I2C_DEBUG_A_SDA_L")
			(options
				(clearance outline)
				(anchor circle)
			)
			(primitives
				(gr_poly
					(pts
						(arc
							(start -0.1778 -0.2794)
							(mid -0.249642 -0.249642)
							(end -0.2794 -0.1778)
						)
						(arc
							(start -0.2794 0.1778)
							(mid -0.249642 0.249642)
							(end -0.1778 0.2794)
						)
						(arc
							(start 0.1778 0.2794)
							(mid 0.249642 0.249642)
							(end 0.2794 0.1778)
						)
						(arc
							(start 0.2794 -0.1778)
							(mid 0.249642 -0.249642)
							(end 0.1778 -0.2794)
						)
					)
					(width 0)
					(fill yes)
				)
			)
		)
	)
	(footprint ""
		(layer "F.Cu")
		(at 45.38853 -47.028862 90)
		(property "Reference" "TP4"
			(at 0 0 90)
			(layer "F.SilkS")
			(hide yes)
			(effects
				(font
					(size 1.27 1.27)
				)
			)
		)
		(property "Value" "TPAD28-2-GP"
			(at -0.0127 -2.3495 90)
			(unlocked yes)
			(layer "F.Fab")
			(hide yes)
			(effects
				(font
					(size 2.54 2.54)
					(thickness 0.381)
				)
			)
		)
		(property "Device Type" "TPAD28"
			(at -0.0127 -3.8735 90)
			(unlocked yes)
			(layer "F.Fab")
			(hide yes)
			(effects
				(font
					(size 2.54 2.54)
					(thickness 0.381)
				)
			)
		)
		(duplicate_pad_numbers_are_jumpers no)
		(fp_poly
			(pts
				(arc
					(start 0 0.3556)
					(mid 0 -0.3556)
					(end 0 0.3556)
				)
			)
			(stroke
				(width 0)
				(type default)
			)
			(fill no)
			(layer "F.CrtYd")
		)
		(fp_poly
			(pts
				(arc
					(start 0 0.6096)
					(mid 0 -0.6096)
					(end 0 0.6096)
				)
			)
			(stroke
				(width 0)
				(type default)
			)
			(fill no)
			(layer "F.Fab")
		)
		(pad "1" smd circle
			(at 0 0 90)
			(size 0.7112 0.7112)
			(layers "F.Cu" "F.Mask" "F.Paste")
			(net "DEBUG_USB_B_DN")
		)
	)
	(footprint ""
		(layer "F.Cu")
		(at 25.222454 -8.264398 -90)
		(property "Reference" "R19"
			(at 0 0 270)
			(layer "F.SilkS")
			(hide yes)
			(effects
				(font
					(size 1.27 1.27)
				)
			)
		)
		(property "Value" "0R2J-2-GP"
			(at 0.064008 -3.993896 270)
			(unlocked yes)
			(layer "F.Fab")
			(hide yes)
			(effects
				(font
					(size 1.016 1.016)
					(thickness 0.1524)
				)
			)
		)
		(property "Device Type" "R402H16"
			(at 0.064008 -5.517896 270)
			(unlocked yes)
			(layer "F.Fab")
			(hide yes)
			(effects
				(font
					(size 1.016 1.016)
					(thickness 0.1524)
				)
			)
		)
		(duplicate_pad_numbers_are_jumpers no)
		(fp_line
			(start -0.508 -0.9398)
			(end -0.508 0.9398)
			(stroke
				(width 0.1524)
				(type default)
			)
			(layer "F.SilkS")
		)
		(fp_line
			(start 0.508 -0.9398)
			(end -0.508 -0.9398)
			(stroke
				(width 0.1524)
				(type default)
			)
			(layer "F.SilkS")
		)
		(fp_rect
			(start -0.508 0.9398)
			(end 0.508 -0.9398)
			(stroke
				(width 0)
				(type default)
			)
			(fill no)
			(layer "F.CrtYd")
		)
		(fp_rect
			(start -0.508 0.9398)
			(end 0.508 -0.9398)
			(stroke
				(width 0)
				(type default)
			)
			(fill no)
			(layer "F.Fab")
		)
		(pad "1" smd custom
			(at 0 -0.4445 270)
			(size 0.1397 0.1397)
			(layers "F.Cu" "F.Mask" "F.Paste")
			(net "D_FLIP_PRE_A#")
			(options
				(clearance outline)
				(anchor circle)
			)
			(primitives
				(gr_poly
					(pts
						(arc
							(start -0.1778 -0.2794)
							(mid -0.249642 -0.249642)
							(end -0.2794 -0.1778)
						)
						(arc
							(start -0.2794 0.1778)
							(mid -0.249642 0.249642)
							(end -0.1778 0.2794)
						)
						(arc
							(start 0.1778 0.2794)
							(mid 0.249642 0.249642)
							(end 0.2794 0.1778)
						)
						(arc
							(start 0.2794 -0.1778)
							(mid 0.249642 -0.249642)
							(end 0.1778 -0.2794)
						)
					)
					(width 0)
					(fill yes)
				)
			)
		)
		(pad "2" smd custom
			(at 0 0.4445 270)
			(size 0.1397 0.1397)
			(layers "F.Cu" "F.Mask" "F.Paste")
			(net "P3V3_STBY_A")
			(options
				(clearance outline)
				(anchor circle)
			)
			(primitives
				(gr_poly
					(pts
						(arc
							(start -0.1778 -0.2794)
							(mid -0.249642 -0.249642)
							(end -0.2794 -0.1778)
						)
						(arc
							(start -0.2794 0.1778)
							(mid -0.249642 0.249642)
							(end -0.1778 0.2794)
						)
						(arc
							(start 0.1778 0.2794)
							(mid 0.249642 0.249642)
							(end 0.2794 0.1778)
						)
						(arc
							(start 0.2794 -0.1778)
							(mid 0.249642 -0.249642)
							(end 0.1778 -0.2794)
						)
					)
					(width 0)
					(fill yes)
				)
			)
		)
	)
	(footprint ""
		(layer "F.Cu")
		(at 13.97 -8.2042 90)
		(property "Reference" "R59"
			(at 0 0 90)
			(layer "F.SilkS")
			(hide yes)
			(effects
				(font
					(size 1.27 1.27)
				)
			)
		)
		(property "Value" "100KR2F-L1-GP"
			(at 0.064008 -3.993896 90)
			(unlocked yes)
			(layer "F.Fab")
			(hide yes)
			(effects
				(font
					(size 1.016 1.016)
					(thickness 0.1524)
				)
			)
		)
		(property "Device Type" "R402H16"
			(at 0.064008 -5.517896 90)
			(unlocked yes)
			(layer "F.Fab")
			(hide yes)
			(effects
				(font
					(size 1.016 1.016)
					(thickness 0.1524)
				)
			)
		)
		(duplicate_pad_numbers_are_jumpers no)
		(fp_line
			(start 0.508 -0.9398)
			(end -0.508 -0.9398)
			(stroke
				(width 0.1524)
				(type default)
			)
			(layer "F.SilkS")
		)
		(fp_line
			(start -0.508 -0.9398)
			(end -0.508 0.9398)
			(stroke
				(width 0.1524)
				(type default)
			)
			(layer "F.SilkS")
		)
		(fp_rect
			(start -0.508 0.9398)
			(end 0.508 -0.9398)
			(stroke
				(width 0)
				(type default)
			)
			(fill no)
			(layer "F.CrtYd")
		)
		(fp_rect
			(start -0.508 0.9398)
			(end 0.508 -0.9398)
			(stroke
				(width 0)
				(type default)
			)
			(fill no)
			(layer "F.Fab")
		)
		(pad "1" smd custom
			(at 0 -0.4445 90)
			(size 0.1397 0.1397)
			(layers "F.Cu" "F.Mask" "F.Paste")
			(net "DEBUG_CARD_A_PRSNT")
			(options
				(clearance outline)
				(anchor circle)
			)
			(primitives
				(gr_poly
					(pts
						(arc
							(start -0.1778 -0.2794)
							(mid -0.249642 -0.249642)
							(end -0.2794 -0.1778)
						)
						(arc
							(start -0.2794 0.1778)
							(mid -0.249642 0.249642)
							(end -0.1778 0.2794)
						)
						(arc
							(start 0.1778 0.2794)
							(mid 0.249642 0.249642)
							(end 0.2794 0.1778)
						)
						(arc
							(start 0.2794 -0.1778)
							(mid 0.249642 -0.249642)
							(end 0.1778 -0.2794)
						)
					)
					(width 0)
					(fill yes)
				)
			)
		)
		(pad "2" smd custom
			(at 0 0.4445 90)
			(size 0.1397 0.1397)
			(layers "F.Cu" "F.Mask" "F.Paste")
			(net "GND")
			(options
				(clearance outline)
				(anchor circle)
			)
			(primitives
				(gr_poly
					(pts
						(arc
							(start -0.1778 -0.2794)
							(mid -0.249642 -0.249642)
							(end -0.2794 -0.1778)
						)
						(arc
							(start -0.2794 0.1778)
							(mid -0.249642 0.249642)
							(end -0.1778 0.2794)
						)
						(arc
							(start 0.1778 0.2794)
							(mid 0.249642 0.249642)
							(end 0.2794 0.1778)
						)
						(arc
							(start 0.2794 -0.1778)
							(mid 0.249642 -0.249642)
							(end 0.1778 -0.2794)
						)
					)
					(width 0)
					(fill yes)
				)
			)
		)
	)
	(footprint ""
		(layer "F.Cu")
		(at 2.131568 -52.79644 90)
		(property "Reference" "TP2"
			(at 0 0 90)
			(layer "F.SilkS")
			(hide yes)
			(effects
				(font
					(size 1.27 1.27)
				)
			)
		)
		(property "Value" "TPAD28-2-GP"
			(at -0.0127 -2.3495 90)
			(unlocked yes)
			(layer "F.Fab")
			(hide yes)
			(effects
				(font
					(size 2.54 2.54)
					(thickness 0.381)
				)
			)
		)
		(property "Device Type" "TPAD28"
			(at -0.0127 -3.8735 90)
			(unlocked yes)
			(layer "F.Fab")
			(hide yes)
			(effects
				(font
					(size 2.54 2.54)
					(thickness 0.381)
				)
			)
		)
		(duplicate_pad_numbers_are_jumpers no)
		(fp_poly
			(pts
				(arc
					(start 0 0.3556)
					(mid 0 -0.3556)
					(end 0 0.3556)
				)
			)
			(stroke
				(width 0)
				(type default)
			)
			(fill no)
			(layer "F.CrtYd")
		)
		(fp_poly
			(pts
				(arc
					(start 0 0.6096)
					(mid 0 -0.6096)
					(end 0 0.6096)
				)
			)
			(stroke
				(width 0)
				(type default)
			)
			(fill no)
			(layer "F.Fab")
		)
		(pad "1" smd circle
			(at 0 0 90)
			(size 0.7112 0.7112)
			(layers "F.Cu" "F.Mask" "F.Paste")
			(net "DEBUG_USB_A_DP")
		)
	)
	(footprint ""
		(layer "F.Cu")
		(at 30.0482 -5.969 -90)
		(property "Reference" "R80"
			(at 0 0 270)
			(layer "F.SilkS")
			(hide yes)
			(effects
				(font
					(size 1.27 1.27)
				)
			)
		)
		(property "Value" "4K7R2F-GP"
			(at 0.064008 -3.993896 270)
			(unlocked yes)
			(layer "F.Fab")
			(hide yes)
			(effects
				(font
					(size 1.016 1.016)
					(thickness 0.1524)
				)
			)
		)
		(property "Device Type" "R402H16"
			(at 0.064008 -5.517896 270)
			(unlocked yes)
			(layer "F.Fab")
			(hide yes)
			(effects
				(font
					(size 1.016 1.016)
					(thickness 0.1524)
				)
			)
		)
		(duplicate_pad_numbers_are_jumpers no)
		(fp_line
			(start -0.508 -0.9398)
			(end -0.508 0.9398)
			(stroke
				(width 0.1524)
				(type default)
			)
			(layer "F.SilkS")
		)
		(fp_line
			(start 0.508 -0.9398)
			(end -0.508 -0.9398)
			(stroke
				(width 0.1524)
				(type default)
			)
			(layer "F.SilkS")
		)
		(fp_rect
			(start -0.508 0.9398)
			(end 0.508 -0.9398)
			(stroke
				(width 0)
				(type default)
			)
			(fill no)
			(layer "F.CrtYd")
		)
		(fp_rect
			(start -0.508 0.9398)
			(end 0.508 -0.9398)
			(stroke
				(width 0)
				(type default)
			)
			(fill no)
			(layer "F.Fab")
		)
		(pad "1" smd custom
			(at 0 -0.4445 270)
			(size 0.1397 0.1397)
			(layers "F.Cu" "F.Mask" "F.Paste")
			(net "P3V3_STBY_B")
			(options
				(clearance outline)
				(anchor circle)
			)
			(primitives
				(gr_poly
					(pts
						(arc
							(start -0.1778 -0.2794)
							(mid -0.249642 -0.249642)
							(end -0.2794 -0.1778)
						)
						(arc
							(start -0.2794 0.1778)
							(mid -0.249642 0.249642)
							(end -0.1778 0.2794)
						)
						(arc
							(start 0.1778 0.2794)
							(mid 0.249642 0.249642)
							(end 0.2794 0.1778)
						)
						(arc
							(start 0.2794 -0.1778)
							(mid 0.249642 -0.249642)
							(end 0.1778 -0.2794)
						)
					)
					(width 0)
					(fill yes)
				)
			)
		)
		(pad "2" smd custom
			(at 0 0.4445 270)
			(size 0.1397 0.1397)
			(layers "F.Cu" "F.Mask" "F.Paste")
			(net "D_FLIP_CLR_B#")
			(options
				(clearance outline)
				(anchor circle)
			)
			(primitives
				(gr_poly
					(pts
						(arc
							(start -0.1778 -0.2794)
							(mid -0.249642 -0.249642)
							(end -0.2794 -0.1778)
						)
						(arc
							(start -0.2794 0.1778)
							(mid -0.249642 0.249642)
							(end -0.1778 0.2794)
						)
						(arc
							(start 0.1778 0.2794)
							(mid 0.249642 0.249642)
							(end 0.2794 0.1778)
						)
						(arc
							(start 0.2794 -0.1778)
							(mid 0.249642 -0.249642)
							(end 0.1778 -0.2794)
						)
					)
					(width 0)
					(fill yes)
				)
			)
		)
	)
	(footprint ""
		(layer "F.Cu")
		(at 50.546 -9.779 90)
		(property "Reference" "U3"
			(at 0 0 90)
			(layer "F.SilkS")
			(hide yes)
			(effects
				(font
					(size 1.27 1.27)
				)
			)
		)
		(property "Value" "TS5A23157DGSR-GP"
			(at 0 -11.811 90)
			(unlocked yes)
			(layer "F.Fab")
			(hide yes)
			(effects
				(font
					(size 2.54 2.54)
					(thickness 0.381)
				)
			)
		)
		(property "Device Type" "MSOP10H44"
			(at 0 -13.335 90)
			(unlocked yes)
			(layer "F.Fab")
			(hide yes)
			(effects
				(font
					(size 2.54 2.54)
					(thickness 0.381)
				)
			)
		)
		(duplicate_pad_numbers_are_jumpers no)
		(fp_line
			(start 1.143 -1.016)
			(end 1.143 1.016)
			(stroke
				(width 0.1524)
				(type default)
			)
			(layer "F.SilkS")
		)
		(fp_line
			(start -2.0066 -1.016)
			(end 1.143 -1.016)
			(stroke
				(width 0.1524)
				(type default)
			)
			(layer "F.SilkS")
		)
		(fp_line
			(start -1.5748 0)
			(end -1.9558 -0.381)
			(stroke
				(width 0.1524)
				(type default)
			)
			(layer "F.SilkS")
		)
		(fp_line
			(start -1.5748 0)
			(end -1.9558 0.381)
			(stroke
				(width 0.1524)
				(type default)
			)
			(layer "F.SilkS")
		)
		(fp_line
			(start 1.143 1.016)
			(end -2.0066 1.016)
			(stroke
				(width 0.1524)
				(type default)
			)
			(layer "F.SilkS")
		)
		(fp_line
			(start -1.8288 1.016)
			(end -1.8288 3.048)
			(stroke
				(width 0.508)
				(type default)
			)
			(layer "F.SilkS")
		)
		(fp_line
			(start -2.0066 1.016)
			(end -2.0066 -1.016)
			(stroke
				(width 0.1524)
				(type default)
			)
			(layer "F.SilkS")
		)
		(fp_poly
			(pts
				(xy -2.0828 3.3401) (xy 2.0828 3.3401) (xy 2.0828 -3.3401) (xy -2.0828 -3.3401)
			)
			(stroke
				(width 0)
				(type default)
			)
			(fill no)
			(layer "F.CrtYd")
		)
		(fp_poly
			(pts
				(xy -2.0828 3.3401) (xy 2.0828 3.3401) (xy 2.0828 -3.3401) (xy -2.0828 -3.3401)
			)
			(stroke
				(width 0)
				(type default)
			)
			(fill no)
			(layer "F.Fab")
		)
		(pad "1" smd rect
			(at -0.99949 2.0701 90)
			(size 0.3048 1.524)
			(layers "F.Cu" "F.Mask" "F.Paste")
			(net "UART_SEL_B_MUX_R")
		)
		(pad "2" smd rect
			(at -0.50038 2.0701 90)
			(size 0.3048 1.524)
			(layers "F.Cu" "F.Mask" "F.Paste")
			(net "UART_EXP_B_TX")
		)
		(pad "3" smd rect
			(at 0 2.0701 90)
			(size 0.3048 1.524)
			(layers "F.Cu" "F.Mask" "F.Paste")
			(net "GND")
		)
		(pad "4" smd rect
			(at 0.50038 2.0701 90)
			(size 0.3048 1.524)
			(layers "F.Cu" "F.Mask" "F.Paste")
			(net "UART_EXP_B_RX")
		)
		(pad "5" smd rect
			(at 0.99949 2.0701 90)
			(size 0.3048 1.524)
			(layers "F.Cu" "F.Mask" "F.Paste")
			(net "UART_SEL_B_MUX_R")
		)
		(pad "6" smd rect
			(at 0.99949 -2.0701 90)
			(size 0.3048 1.524)
			(layers "F.Cu" "F.Mask" "F.Paste")
			(net "UART_B_RX")
		)
		(pad "7" smd rect
			(at 0.50038 -2.0701 90)
			(size 0.3048 1.524)
			(layers "F.Cu" "F.Mask" "F.Paste")
			(net "UART_IOC_B_RX")
		)
		(pad "8" smd rect
			(at 0 -2.0701 90)
			(size 0.3048 1.524)
			(layers "F.Cu" "F.Mask" "F.Paste")
			(net "P3V3_STBY_B")
		)
		(pad "9" smd rect
			(at -0.50038 -2.0701 90)
			(size 0.3048 1.524)
			(layers "F.Cu" "F.Mask" "F.Paste")
			(net "UART_IOC_B_TX")
		)
		(pad "10" smd rect
			(at -0.99949 -2.0701 90)
			(size 0.3048 1.524)
			(layers "F.Cu" "F.Mask" "F.Paste")
			(net "UART_B_TX")
		)
	)
	(footprint ""
		(layer "F.Cu")
		(at 2.2987 -49.149)
		(property "Reference" "R31"
			(at 0 0 0)
			(layer "F.SilkS")
			(hide yes)
			(effects
				(font
					(size 1.27 1.27)
				)
			)
		)
		(property "Value" "0R2J-2-GP"
			(at 0.064008 -4.679696 0)
			(unlocked yes)
			(layer "F.Fab")
			(hide yes)
			(effects
				(font
					(size 2.54 2.54)
					(thickness 0.381)
				)
			)
		)
		(property "Device Type" "R402H16"
			(at 0.064008 -6.203696 0)
			(unlocked yes)
			(layer "F.Fab")
			(hide yes)
			(effects
				(font
					(size 2.54 2.54)
					(thickness 0.381)
				)
			)
		)
		(duplicate_pad_numbers_are_jumpers no)
		(fp_line
			(start -0.508 -0.9398)
			(end -0.508 0.9398)
			(stroke
				(width 0.1524)
				(type default)
			)
			(layer "F.SilkS")
		)
		(fp_line
			(start 0.508 -0.9398)
			(end -0.508 -0.9398)
			(stroke
				(width 0.1524)
				(type default)
			)
			(layer "F.SilkS")
		)
		(fp_rect
			(start -0.508 0.9398)
			(end 0.508 -0.9398)
			(stroke
				(width 0)
				(type default)
			)
			(fill no)
			(layer "F.CrtYd")
		)
		(fp_rect
			(start -0.508 0.9398)
			(end 0.508 -0.9398)
			(stroke
				(width 0)
				(type default)
			)
			(fill no)
			(layer "F.Fab")
		)
		(pad "1" smd custom
			(at 0 -0.4445)
			(size 0.1397 0.1397)
			(layers "F.Cu" "F.Mask" "F.Paste")
			(net "TEMP_1_SDA")
			(options
				(clearance outline)
				(anchor circle)
			)
			(primitives
				(gr_poly
					(pts
						(arc
							(start -0.1778 -0.2794)
							(mid -0.249642 -0.249642)
							(end -0.2794 -0.1778)
						)
						(arc
							(start -0.2794 0.1778)
							(mid -0.249642 0.249642)
							(end -0.1778 0.2794)
						)
						(arc
							(start 0.1778 0.2794)
							(mid 0.249642 0.249642)
							(end 0.2794 0.1778)
						)
						(arc
							(start 0.2794 -0.1778)
							(mid 0.249642 -0.249642)
							(end 0.1778 -0.2794)
						)
					)
					(width 0)
					(fill yes)
				)
			)
		)
		(pad "2" smd custom
			(at 0 0.4445)
			(size 0.1397 0.1397)
			(layers "F.Cu" "F.Mask" "F.Paste")
			(net "I2C_DPB_A_SDA")
			(options
				(clearance outline)
				(anchor circle)
			)
			(primitives
				(gr_poly
					(pts
						(arc
							(start -0.1778 -0.2794)
							(mid -0.249642 -0.249642)
							(end -0.2794 -0.1778)
						)
						(arc
							(start -0.2794 0.1778)
							(mid -0.249642 0.249642)
							(end -0.1778 0.2794)
						)
						(arc
							(start 0.1778 0.2794)
							(mid 0.249642 0.249642)
							(end 0.2794 0.1778)
						)
						(arc
							(start 0.2794 -0.1778)
							(mid 0.249642 -0.249642)
							(end 0.1778 -0.2794)
						)
					)
					(width 0)
					(fill yes)
				)
			)
		)
	)
)
